(kicad_pcb
	(version 20260206)
	(generator "pcbnew")
	(generator_version "10.0")
	(general
		(thickness 1.6)
		(legacy_teardrops no)
	)
	(paper "A4")
	(title_block
		(title "peb — Lightning_PEB_BRD.brd")
		(comment 1 "Lightning (Wiwynn / Facebook NVMe JBOF) / footprints 1381-1388 of 2563")
	)
	(layers
		(0 "F.Cu" signal "TOP")
		(4 "In1.Cu" signal "L2GND")
		(6 "In2.Cu" signal "L3")
		(8 "In3.Cu" signal "L4VCC")
		(10 "In4.Cu" signal "L5VCC")
		(12 "In5.Cu" signal "L6")
		(14 "In6.Cu" signal "L7GND")
		(2 "B.Cu" signal "BOTTOM")
		(9 "F.Adhes" user "F.Adhesive")
		(11 "B.Adhes" user "B.Adhesive")
		(13 "F.Paste" user "Package Geometry/Pastemask Top")
		(15 "B.Paste" user "Package Geometry/Pastemask Bottom")
		(5 "F.SilkS" user "Ref Des/Silkscreen Top")
		(7 "B.SilkS" user "Ref Des/Silkscreen Bottom")
		(1 "F.Mask" user "Board Geometry/Soldermask Top")
		(3 "B.Mask" user "Board Geometry/Soldermask Bottom")
		(17 "Dwgs.User" user "User.Drawings")
		(19 "Cmts.User" user "User.Comments")
		(21 "Eco1.User" user "User.Eco1")
		(23 "Eco2.User" user "User.Eco2")
		(25 "Edge.Cuts" user "Board Geometry/Outline")
		(27 "Margin" user)
		(31 "F.CrtYd" user "Package Geometry/Place Bound Top")
		(29 "B.CrtYd" user "Package Geometry/Place Bound Bottom")
		(35 "F.Fab" user "Ref Des/Assembly Top")
		(33 "B.Fab" user "Ref Des/Assembly Bottom")
	)
	(footprint ""
		(layer "F.Cu")
		(at 57.15 -132.1054)
		(property "Reference" "R3098"
			(at 0 0 0)
			(layer "F.SilkS")
			(hide yes)
			(effects
				(font
					(size 1.27 1.27)
				)
			)
		)
		(property "Value" "1KR2F-3-GP"
			(at 0.064008 -3.993896 0)
			(unlocked yes)
			(layer "F.Fab")
			(hide yes)
			(effects
				(font
					(size 1.016 1.016)
					(thickness 0.1524)
				)
			)
		)
		(property "Device Type" "R402H16"
			(at 0.064008 -5.517896 0)
			(unlocked yes)
			(layer "F.Fab")
			(hide yes)
			(effects
				(font
					(size 1.016 1.016)
					(thickness 0.1524)
				)
			)
		)
		(duplicate_pad_numbers_are_jumpers no)
		(fp_line
			(start -0.508 -0.9398)
			(end -0.508 0.9398)
			(stroke
				(width 0.1524)
				(type default)
			)
			(layer "F.SilkS")
		)
		(fp_line
			(start 0.508 -0.9398)
			(end -0.508 -0.9398)
			(stroke
				(width 0.1524)
				(type default)
			)
			(layer "F.SilkS")
		)
		(fp_rect
			(start -0.508 0.9398)
			(end 0.508 -0.9398)
			(stroke
				(width 0)
				(type default)
			)
			(fill no)
			(layer "F.CrtYd")
		)
		(fp_rect
			(start -0.508 0.9398)
			(end 0.508 -0.9398)
			(stroke
				(width 0)
				(type default)
			)
			(fill no)
			(layer "F.Fab")
		)
		(pad "1" smd custom
			(at 0 -0.4445)
			(size 0.1397 0.1397)
			(layers "F.Cu" "F.Mask" "F.Paste")
			(net "ADC_P1V53V")
			(options
				(clearance outline)
				(anchor circle)
			)
			(primitives
				(gr_poly
					(pts
						(arc
							(start -0.1778 -0.2794)
							(mid -0.249642 -0.249642)
							(end -0.2794 -0.1778)
						)
						(arc
							(start -0.2794 0.1778)
							(mid -0.249642 0.249642)
							(end -0.1778 0.2794)
						)
						(arc
							(start 0.1778 0.2794)
							(mid 0.249642 0.249642)
							(end 0.2794 0.1778)
						)
						(arc
							(start 0.2794 -0.1778)
							(mid 0.249642 -0.249642)
							(end 0.1778 -0.2794)
						)
					)
					(width 0)
					(fill yes)
				)
			)
		)
		(pad "2" smd custom
			(at 0 0.4445)
			(size 0.1397 0.1397)
			(layers "F.Cu" "F.Mask" "F.Paste")
			(net "GND")
			(options
				(clearance outline)
				(anchor circle)
			)
			(primitives
				(gr_poly
					(pts
						(arc
							(start -0.1778 -0.2794)
							(mid -0.249642 -0.249642)
							(end -0.2794 -0.1778)
						)
						(arc
							(start -0.2794 0.1778)
							(mid -0.249642 0.249642)
							(end -0.1778 0.2794)
						)
						(arc
							(start 0.1778 0.2794)
							(mid 0.249642 0.249642)
							(end 0.2794 0.1778)
						)
						(arc
							(start 0.2794 -0.1778)
							(mid 0.249642 -0.249642)
							(end 0.1778 -0.2794)
						)
					)
					(width 0)
					(fill yes)
				)
			)
		)
	)
	(footprint ""
		(layer "F.Cu")
		(at 31.369 -43.942 -90)
		(property "Reference" "C238"
			(at 0 0 270)
			(layer "F.SilkS")
			(hide yes)
			(effects
				(font
					(size 1.27 1.27)
				)
			)
		)
		(property "Value" "SCD1U16V2JX-1-GP"
			(at 1.1811 -2.7051 270)
			(unlocked yes)
			(layer "F.Fab")
			(hide yes)
			(effects
				(font
					(size 1.016 1.016)
					(thickness 0.1524)
				)
			)
		)
		(property "Device Type" "C402H22"
			(at 1.1811 -4.2291 270)
			(unlocked yes)
			(layer "F.Fab")
			(hide yes)
			(effects
				(font
					(size 1.016 1.016)
					(thickness 0.1524)
				)
			)
		)
		(duplicate_pad_numbers_are_jumpers no)
		(fp_rect
			(start -0.4318 0.9525)
			(end 0.4318 -0.9525)
			(stroke
				(width 0)
				(type default)
			)
			(fill no)
			(layer "F.CrtYd")
		)
		(fp_rect
			(start -0.4318 0.9525)
			(end 0.4318 -0.9525)
			(stroke
				(width 0)
				(type default)
			)
			(fill no)
			(layer "F.Fab")
		)
		(pad "1" smd custom
			(at 0 -0.4445 270)
			(size 0.1524 0.1524)
			(layers "F.Cu" "F.Mask" "F.Paste")
			(net "P5V_USB")
			(options
				(clearance outline)
				(anchor circle)
			)
			(primitives
				(gr_poly
					(pts
						(arc
							(start 0.3048 -0.2032)
							(mid 0.275042 -0.275042)
							(end 0.2032 -0.3048)
						)
						(arc
							(start -0.2032 -0.3048)
							(mid -0.275042 -0.275042)
							(end -0.3048 -0.2032)
						)
						(arc
							(start -0.3048 0.2032)
							(mid -0.275042 0.275042)
							(end -0.2032 0.3048)
						)
						(arc
							(start 0.2032 0.3048)
							(mid 0.275042 0.275042)
							(end 0.3048 0.2032)
						)
					)
					(width 0)
					(fill yes)
				)
			)
		)
		(pad "2" smd custom
			(at 0 0.4445 270)
			(size 0.1524 0.1524)
			(layers "F.Cu" "F.Mask" "F.Paste")
			(net "GND")
			(options
				(clearance outline)
				(anchor circle)
			)
			(primitives
				(gr_poly
					(pts
						(arc
							(start 0.3048 -0.2032)
							(mid 0.275042 -0.275042)
							(end 0.2032 -0.3048)
						)
						(arc
							(start -0.2032 -0.3048)
							(mid -0.275042 -0.275042)
							(end -0.3048 -0.2032)
						)
						(arc
							(start -0.3048 0.2032)
							(mid -0.275042 0.275042)
							(end -0.2032 0.3048)
						)
						(arc
							(start 0.2032 0.3048)
							(mid 0.275042 0.275042)
							(end 0.3048 0.2032)
						)
					)
					(width 0)
					(fill yes)
				)
			)
		)
	)
	(footprint ""
		(layer "F.Cu")
		(at 195.600066 0 90)
		(property "Reference" "LED4"
			(at 0 0 90)
			(layer "F.SilkS")
			(hide yes)
			(effects
				(font
					(size 1.27 1.27)
				)
			)
		)
		(property "Value" "LED-R-126-GP-U2"
			(at -4.444492 -2.4384 90)
			(unlocked yes)
			(layer "F.Fab")
			(hide yes)
			(effects
				(font
					(size 1.016 1.016)
					(thickness 0.1524)
				)
			)
		)
		(property "Device Type" "LED3020-1A2K-1H44"
			(at -4.444492 -3.9624 90)
			(unlocked yes)
			(layer "F.Fab")
			(hide yes)
			(effects
				(font
					(size 1.016 1.016)
					(thickness 0.1524)
				)
			)
		)
		(duplicate_pad_numbers_are_jumpers no)
		(fp_line
			(start 0.9271 -2.1463)
			(end 0.9271 2.1463)
			(stroke
				(width 0.1524)
				(type default)
			)
			(layer "F.SilkS")
		)
		(fp_line
			(start -0.9271 -2.1463)
			(end 0.9271 -2.1463)
			(stroke
				(width 0.1524)
				(type default)
			)
			(layer "F.SilkS")
		)
		(fp_line
			(start -0.9271 -1.16078)
			(end -0.9271 -2.1463)
			(stroke
				(width 0.1524)
				(type default)
			)
			(layer "F.SilkS")
		)
		(fp_line
			(start 1.1176 1.3462)
			(end 1.1176 2.3241)
			(stroke
				(width 0.508)
				(type default)
			)
			(layer "F.SilkS")
		)
		(fp_line
			(start 0.9271 2.1463)
			(end -0.9271 2.1463)
			(stroke
				(width 0.1524)
				(type default)
			)
			(layer "F.SilkS")
		)
		(fp_line
			(start -0.9271 2.1463)
			(end -0.9271 1.160526)
			(stroke
				(width 0.1524)
				(type default)
			)
			(layer "F.SilkS")
		)
		(fp_line
			(start 1.1176 2.3241)
			(end -1.1176 2.3241)
			(stroke
				(width 0.508)
				(type default)
			)
			(layer "F.SilkS")
		)
		(fp_line
			(start -1.1176 2.3241)
			(end -1.1176 1.397)
			(stroke
				(width 0.508)
				(type default)
			)
			(layer "F.SilkS")
		)
		(fp_arc
			(start -0.9271 1.160526)
			(mid -1.701058 -0.000049)
			(end -0.9271 -1.16078)
			(stroke
				(width 0.1524)
				(type default)
			)
			(layer "F.SilkS")
		)
		(fp_poly
			(pts
				(xy -0.5461 1.4986)
				(arc
					(start -0.5461 0.997966)
					(mid -1.447396 -0.000013)
					(end -0.5461 -0.99822)
				)
				(xy -0.5461 -1.4986) (xy 0.5461 -1.4986) (xy 0.5461 1.4986)
			)
			(stroke
				(width 0)
				(type default)
			)
			(fill no)
			(layer "F.CrtYd")
		)
		(fp_poly
			(pts
				(xy -1.1811 2.2225)
				(arc
					(start -1.1811 1.319276)
					(mid -1.955222 -0.000062)
					(end -1.1811 -1.31953)
				)
				(xy -1.1811 -2.2225) (xy 1.1811 -2.2225) (xy 1.1811 -0.00635) (xy 0.5461 -0.00635) (xy 0.5461 -1.4986)
				(xy -0.5461 -1.4986)
				(arc
					(start -0.5461 -0.99822)
					(mid -1.447649 0)
					(end -0.5461 0.99822)
				)
				(xy -0.5461 1.4986) (xy 0.5461 1.4986) (xy 0.5461 0.00635) (xy 1.1811 0.00635) (xy 1.1811 2.2225)
			)
			(stroke
				(width 0)
				(type default)
			)
			(fill no)
			(layer "F.CrtYd")
		)
		(fp_poly
			(pts
				(xy -1.1811 2.2225)
				(arc
					(start -1.1811 1.319276)
					(mid -1.955222 -0.000062)
					(end -1.1811 -1.31953)
				)
				(xy -1.1811 -2.2225) (xy 1.1811 -2.2225) (xy 1.1811 2.2225)
			)
			(stroke
				(width 0)
				(type default)
			)
			(fill no)
			(layer "F.Fab")
		)
		(pad "1A" smd rect
			(at 0 -1.366774 90)
			(size 1.3462 1.0414)
			(layers "F.Cu" "F.Mask" "F.Paste")
			(net "ENCLO_LED_RED_R")
		)
		(pad "2K" smd rect
			(at 0 1.366774 90)
			(size 1.3462 1.0414)
			(layers "F.Cu" "F.Mask" "F.Paste")
			(net "ENCLO_LED_RED")
		)
	)
	(footprint ""
		(layer "F.Cu")
		(at 331.756512 -172.432218 180)
		(property "Reference" "R574"
			(at 0 0 180)
			(layer "F.SilkS")
			(hide yes)
			(effects
				(font
					(size 1.27 1.27)
				)
			)
		)
		(property "Value" "10KR2F-2-GP"
			(at 0.064008 -3.993896 180)
			(unlocked yes)
			(layer "F.Fab")
			(hide yes)
			(effects
				(font
					(size 1.016 1.016)
					(thickness 0.1524)
				)
			)
		)
		(property "Device Type" "R402H16"
			(at 0.064008 -5.517896 180)
			(unlocked yes)
			(layer "F.Fab")
			(hide yes)
			(effects
				(font
					(size 1.016 1.016)
					(thickness 0.1524)
				)
			)
		)
		(duplicate_pad_numbers_are_jumpers no)
		(fp_line
			(start 0.508 -0.9398)
			(end -0.508 -0.9398)
			(stroke
				(width 0.1524)
				(type default)
			)
			(layer "F.SilkS")
		)
		(fp_line
			(start -0.508 -0.9398)
			(end -0.508 0.9398)
			(stroke
				(width 0.1524)
				(type default)
			)
			(layer "F.SilkS")
		)
		(fp_rect
			(start -0.508 0.9398)
			(end 0.508 -0.9398)
			(stroke
				(width 0)
				(type default)
			)
			(fill no)
			(layer "F.CrtYd")
		)
		(fp_rect
			(start -0.508 0.9398)
			(end 0.508 -0.9398)
			(stroke
				(width 0)
				(type default)
			)
			(fill no)
			(layer "F.Fab")
		)
		(pad "1" smd custom
			(at 0 -0.4445 180)
			(size 0.1397 0.1397)
			(layers "F.Cu" "F.Mask" "F.Paste")
			(net "GND")
			(options
				(clearance outline)
				(anchor circle)
			)
			(primitives
				(gr_poly
					(pts
						(arc
							(start -0.1778 -0.2794)
							(mid -0.249642 -0.249642)
							(end -0.2794 -0.1778)
						)
						(arc
							(start -0.2794 0.1778)
							(mid -0.249642 0.249642)
							(end -0.1778 0.2794)
						)
						(arc
							(start 0.1778 0.2794)
							(mid 0.249642 0.249642)
							(end 0.2794 0.1778)
						)
						(arc
							(start 0.2794 -0.1778)
							(mid 0.249642 -0.249642)
							(end 0.1778 -0.2794)
						)
					)
					(width 0)
					(fill yes)
				)
			)
		)
		(pad "2" smd custom
			(at 0 0.4445 180)
			(size 0.1397 0.1397)
			(layers "F.Cu" "F.Mask" "F.Paste")
			(net "IOEXP4_AD2")
			(options
				(clearance outline)
				(anchor circle)
			)
			(primitives
				(gr_poly
					(pts
						(arc
							(start -0.1778 -0.2794)
							(mid -0.249642 -0.249642)
							(end -0.2794 -0.1778)
						)
						(arc
							(start -0.2794 0.1778)
							(mid -0.249642 0.249642)
							(end -0.1778 0.2794)
						)
						(arc
							(start 0.1778 0.2794)
							(mid 0.249642 0.249642)
							(end 0.2794 0.1778)
						)
						(arc
							(start 0.2794 -0.1778)
							(mid 0.249642 -0.249642)
							(end 0.1778 -0.2794)
						)
					)
					(width 0)
					(fill yes)
				)
			)
		)
	)
	(footprint ""
		(layer "F.Cu")
		(at 56.769 -152.781 90)
		(property "Reference" "TP166"
			(at 0 0 90)
			(layer "F.SilkS")
			(hide yes)
			(effects
				(font
					(size 1.27 1.27)
				)
			)
		)
		(property "Value" "TPAD32-GP"
			(at -0.0508 -1.6764 90)
			(unlocked yes)
			(layer "F.Fab")
			(hide yes)
			(effects
				(font
					(size 1.016 1.016)
					(thickness 0.1524)
				)
			)
		)
		(property "Device Type" "TPAD32"
			(at -0.0508 -3.2004 90)
			(unlocked yes)
			(layer "F.Fab")
			(hide yes)
			(effects
				(font
					(size 1.016 1.016)
					(thickness 0.1524)
				)
			)
		)
		(duplicate_pad_numbers_are_jumpers no)
		(fp_poly
			(pts
				(arc
					(start 0 0.4064)
					(mid 0 -0.4064)
					(end 0 0.4064)
				)
			)
			(stroke
				(width 0)
				(type default)
			)
			(fill no)
			(layer "F.CrtYd")
		)
		(fp_poly
			(pts
				(arc
					(start 0 0.7112)
					(mid 0 -0.7112)
					(end 0 0.7112)
				)
			)
			(stroke
				(width 0)
				(type default)
			)
			(fill no)
			(layer "F.Fab")
		)
		(pad "1" smd circle
			(at 0 0 90)
			(size 0.8128 0.8128)
			(layers "F.Cu" "F.Mask" "F.Paste")
			(net "TEMP_2_ALERT")
		)
	)
	(footprint ""
		(layer "F.Cu")
		(at 310.007 -57.8866)
		(property "Reference" "PG46"
			(at 0 0 0)
			(layer "F.SilkS")
			(hide yes)
			(effects
				(font
					(size 1.27 1.27)
				)
			)
		)
		(property "Value" "GAP-CLOSE-PWR-3-GP"
			(at 0.0254 -6.5786 0)
			(unlocked yes)
			(layer "F.Fab")
			(hide yes)
			(effects
				(font
					(size 1.016 1.016)
					(thickness 0.1524)
				)
			)
		)
		(property "Device Type" "GAP-CLOSE-PWR-3"
			(at 0.0254 -8.255 0)
			(unlocked yes)
			(layer "F.Fab")
			(hide yes)
			(effects
				(font
					(size 1.016 1.016)
					(thickness 0.1524)
				)
			)
		)
		(duplicate_pad_numbers_are_jumpers no)
		(fp_rect
			(start -0.7112 0.4572)
			(end 0.7112 -0.4572)
			(stroke
				(width 0)
				(type default)
			)
			(fill no)
			(layer "F.CrtYd")
		)
		(fp_poly
			(pts
				(xy -0.7112 -0.4572) (xy 0.7112 -0.4572) (xy 0.7112 0.4572) (xy -0.7112 0.4572)
			)
			(stroke
				(width 0)
				(type default)
			)
			(fill no)
			(layer "F.Fab")
		)
		(pad "1" smd rect
			(at -0.3048 0)
			(size 0.6604 0.762)
			(layers "F.Cu" "F.Mask" "F.Paste")
			(net "DUT_VDD")
		)
		(pad "2" smd rect
			(at 0.3048 0)
			(size 0.6604 0.762)
			(layers "F.Cu" "F.Mask" "F.Paste")
			(net "P0V9_E")
		)
	)
	(footprint ""
		(layer "F.Cu")
		(at 38.260528 -114.77117 180)
		(property "Reference" "R286"
			(at 0 0 180)
			(layer "F.SilkS")
			(hide yes)
			(effects
				(font
					(size 1.27 1.27)
				)
			)
		)
		(property "Value" "0R2J-2-GP"
			(at 0.064008 -3.993896 180)
			(unlocked yes)
			(layer "F.Fab")
			(hide yes)
			(effects
				(font
					(size 1.016 1.016)
					(thickness 0.1524)
				)
			)
		)
		(property "Device Type" "R402H16"
			(at 0.064008 -5.517896 180)
			(unlocked yes)
			(layer "F.Fab")
			(hide yes)
			(effects
				(font
					(size 1.016 1.016)
					(thickness 0.1524)
				)
			)
		)
		(duplicate_pad_numbers_are_jumpers no)
		(fp_line
			(start 0.508 -0.9398)
			(end -0.508 -0.9398)
			(stroke
				(width 0.1524)
				(type default)
			)
			(layer "F.SilkS")
		)
		(fp_line
			(start -0.508 -0.9398)
			(end -0.508 0.9398)
			(stroke
				(width 0.1524)
				(type default)
			)
			(layer "F.SilkS")
		)
		(fp_rect
			(start -0.508 0.9398)
			(end 0.508 -0.9398)
			(stroke
				(width 0)
				(type default)
			)
			(fill no)
			(layer "F.CrtYd")
		)
		(fp_rect
			(start -0.508 0.9398)
			(end 0.508 -0.9398)
			(stroke
				(width 0)
				(type default)
			)
			(fill no)
			(layer "F.Fab")
		)
		(pad "1" smd custom
			(at 0 -0.4445 180)
			(size 0.1397 0.1397)
			(layers "F.Cu" "F.Mask" "F.Paste")
			(net "RMII_BMC_CRS_DV")
			(options
				(clearance outline)
				(anchor circle)
			)
			(primitives
				(gr_poly
					(pts
						(arc
							(start -0.1778 -0.2794)
							(mid -0.249642 -0.249642)
							(end -0.2794 -0.1778)
						)
						(arc
							(start -0.2794 0.1778)
							(mid -0.249642 0.249642)
							(end -0.1778 0.2794)
						)
						(arc
							(start 0.1778 0.2794)
							(mid 0.249642 0.249642)
							(end 0.2794 0.1778)
						)
						(arc
							(start 0.2794 -0.1778)
							(mid 0.249642 -0.249642)
							(end 0.1778 -0.2794)
						)
					)
					(width 0)
					(fill yes)
				)
			)
		)
		(pad "2" smd custom
			(at 0 0.4445 180)
			(size 0.1397 0.1397)
			(layers "F.Cu" "F.Mask" "F.Paste")
			(net "RMII0_BMC_C_CRS_DV")
			(options
				(clearance outline)
				(anchor circle)
			)
			(primitives
				(gr_poly
					(pts
						(arc
							(start -0.1778 -0.2794)
							(mid -0.249642 -0.249642)
							(end -0.2794 -0.1778)
						)
						(arc
							(start -0.2794 0.1778)
							(mid -0.249642 0.249642)
							(end -0.1778 0.2794)
						)
						(arc
							(start 0.1778 0.2794)
							(mid 0.249642 0.249642)
							(end 0.2794 0.1778)
						)
						(arc
							(start 0.2794 -0.1778)
							(mid 0.249642 -0.249642)
							(end 0.1778 -0.2794)
						)
					)
					(width 0)
					(fill yes)
				)
			)
		)
	)
	(footprint ""
		(layer "F.Cu")
		(at 7.9248 -180.5686 180)
		(property "Reference" "R2099"
			(at 0 0 180)
			(layer "F.SilkS")
			(hide yes)
			(effects
				(font
					(size 1.27 1.27)
				)
			)
		)
		(property "Value" "39K2R2F-L-GP"
			(at 0.064008 -3.993896 180)
			(unlocked yes)
			(layer "F.Fab")
			(hide yes)
			(effects
				(font
					(size 1.016 1.016)
					(thickness 0.1524)
				)
			)
		)
		(property "Device Type" "R402H16"
			(at 0.064008 -5.517896 180)
			(unlocked yes)
			(layer "F.Fab")
			(hide yes)
			(effects
				(font
					(size 1.016 1.016)
					(thickness 0.1524)
				)
			)
		)
		(duplicate_pad_numbers_are_jumpers no)
		(fp_line
			(start 0.508 -0.9398)
			(end -0.508 -0.9398)
			(stroke
				(width 0.1524)
				(type default)
			)
			(layer "F.SilkS")
		)
		(fp_line
			(start -0.508 -0.9398)
			(end -0.508 0.9398)
			(stroke
				(width 0.1524)
				(type default)
			)
			(layer "F.SilkS")
		)
		(fp_rect
			(start -0.508 0.9398)
			(end 0.508 -0.9398)
			(stroke
				(width 0)
				(type default)
			)
			(fill no)
			(layer "F.CrtYd")
		)
		(fp_rect
			(start -0.508 0.9398)
			(end 0.508 -0.9398)
			(stroke
				(width 0)
				(type default)
			)
			(fill no)
			(layer "F.Fab")
		)
		(pad "1" smd custom
			(at 0 -0.4445 180)
			(size 0.1397 0.1397)
			(layers "F.Cu" "F.Mask" "F.Paste")
			(net "P12V")
			(options
				(clearance outline)
				(anchor circle)
			)
			(primitives
				(gr_poly
					(pts
						(arc
							(start -0.1778 -0.2794)
							(mid -0.249642 -0.249642)
							(end -0.2794 -0.1778)
						)
						(arc
							(start -0.2794 0.1778)
							(mid -0.249642 0.249642)
							(end -0.1778 0.2794)
						)
						(arc
							(start 0.1778 0.2794)
							(mid 0.249642 0.249642)
							(end 0.2794 0.1778)
						)
						(arc
							(start 0.2794 -0.1778)
							(mid 0.249642 -0.249642)
							(end 0.1778 -0.2794)
						)
					)
					(width 0)
					(fill yes)
				)
			)
		)
		(pad "2" smd custom
			(at 0 0.4445 180)
			(size 0.1397 0.1397)
			(layers "F.Cu" "F.Mask" "F.Paste")
			(net "MB0_P12V_PWRGOOD")
			(options
				(clearance outline)
				(anchor circle)
			)
			(primitives
				(gr_poly
					(pts
						(arc
							(start -0.1778 -0.2794)
							(mid -0.249642 -0.249642)
							(end -0.2794 -0.1778)
						)
						(arc
							(start -0.2794 0.1778)
							(mid -0.249642 0.249642)
							(end -0.1778 0.2794)
						)
						(arc
							(start 0.1778 0.2794)
							(mid 0.249642 0.249642)
							(end 0.2794 0.1778)
						)
						(arc
							(start 0.2794 -0.1778)
							(mid 0.249642 -0.249642)
							(end 0.1778 -0.2794)
						)
					)
					(width 0)
					(fill yes)
				)
			)
		)
	)
)
